(kicad_pcb
	(version 20260206)
	(generator "pcbnew")
	(generator_version "10.0")
	(general
		(thickness 1.6)
		(legacy_teardrops no)
	)
	(paper "A4")
	(title_block
		(title "01162023_DA0F0TEBIF0_F0T_Expander_BD_F_brd_V02_OCP.brd")
		(comment 1 "Grand Teton / footprints 4845-4847 of 9728")
	)
	(layers
		(0 "F.Cu" signal "TOP")
		(4 "In1.Cu" signal "GND")
		(6 "In2.Cu" signal "VCC")
		(8 "In3.Cu" signal "VCC1")
		(10 "In4.Cu" signal "GND1")
		(12 "In5.Cu" signal "IN1")
		(14 "In6.Cu" signal "GND2")
		(16 "In7.Cu" signal "IN2")
		(18 "In8.Cu" signal "GND3")
		(20 "In9.Cu" signal "IN3")
		(22 "In10.Cu" signal "GND4")
		(24 "In11.Cu" signal "IN4")
		(26 "In12.Cu" signal "GND5")
		(28 "In13.Cu" signal "IN5")
		(30 "In14.Cu" signal "GND6")
		(32 "In15.Cu" signal "IN6")
		(34 "In16.Cu" signal "GND7")
		(2 "B.Cu" signal "BOTTOM")
		(9 "F.Adhes" user "F.Adhesive")
		(11 "B.Adhes" user "B.Adhesive")
		(13 "F.Paste" user "Package Geometry/Pastemask Top")
		(15 "B.Paste" user "Package Geometry/Pastemask Bottom")
		(5 "F.SilkS" user "Ref Des/Silkscreen Top")
		(7 "B.SilkS" user "Ref Des/Silkscreen Bottom")
		(1 "F.Mask" user "Board Geometry/Soldermask Top")
		(3 "B.Mask" user "Board Geometry/Soldermask Bottom")
		(17 "Dwgs.User" user "User.Drawings")
		(19 "Cmts.User" user "User.Comments")
		(21 "Eco1.User" user "User.Eco1")
		(23 "Eco2.User" user "User.Eco2")
		(25 "Edge.Cuts" user "Board Geometry/Outline")
		(27 "Margin" user)
		(31 "F.CrtYd" user "Package Geometry/Place Bound Top")
		(29 "B.CrtYd" user "Package Geometry/Place Bound Bottom")
		(35 "F.Fab" user "Ref Des/Assembly Top")
		(33 "B.Fab" user "Ref Des/Assembly Bottom")
	)
	(footprint ""
		(layer "F.Cu")
		(at 338.09559 -86.764368)
		(property "Reference" "U116"
			(at 2.136648 -4.159504 0)
			(unlocked yes)
			(layer "F.SilkS")
			(effects
				(font
					(size 0.7874 0.5842)
					(thickness 0.1524)
				)
				(justify left)
			)
		)
		(property "Value" ""
			(at 0 0 0)
			(layer "F.Fab")
			(effects
				(font
					(size 1.27 1.27)
				)
			)
		)
		(duplicate_pad_numbers_are_jumpers no)
		(fp_line
			(start -2.999994 -2.999994)
			(end -2.999994 -2.4384)
			(stroke
				(width 0.1524)
				(type default)
			)
			(layer "F.SilkS")
		)
		(fp_line
			(start -2.999994 2.4384)
			(end -2.999994 2.999994)
			(stroke
				(width 0.1524)
				(type default)
			)
			(layer "F.SilkS")
		)
		(fp_line
			(start -2.999994 2.999994)
			(end -2.4384 2.999994)
			(stroke
				(width 0.1524)
				(type default)
			)
			(layer "F.SilkS")
		)
		(fp_line
			(start -2.4384 -2.999994)
			(end -2.999994 -2.999994)
			(stroke
				(width 0.1524)
				(type default)
			)
			(layer "F.SilkS")
		)
		(fp_line
			(start 2.4384 2.999994)
			(end 2.999994 2.999994)
			(stroke
				(width 0.1524)
				(type default)
			)
			(layer "F.SilkS")
		)
		(fp_line
			(start 2.999994 -2.999994)
			(end 2.4384 -2.999994)
			(stroke
				(width 0.1524)
				(type default)
			)
			(layer "F.SilkS")
		)
		(fp_line
			(start 2.999994 -2.4384)
			(end 2.999994 -2.999994)
			(stroke
				(width 0.1524)
				(type default)
			)
			(layer "F.SilkS")
		)
		(fp_line
			(start 2.999994 2.999994)
			(end 2.999994 2.4384)
			(stroke
				(width 0.1524)
				(type default)
			)
			(layer "F.SilkS")
		)
		(fp_poly
			(pts
				(xy -4.674362 -2.064766) (xy -4.674362 -2.834132) (xy -3.904996 -2.449322)
			)
			(stroke
				(width 0)
				(type default)
			)
			(fill yes)
			(layer "F.SilkS")
		)
		(fp_line
			(start -2.999994 -2.999994)
			(end -2.999994 2.999994)
			(stroke
				(width 0.1)
				(type default)
			)
			(layer "F.Fab")
		)
		(fp_line
			(start -2.999994 2.999994)
			(end 2.999994 2.999994)
			(stroke
				(width 0.1)
				(type default)
			)
			(layer "F.Fab")
		)
		(fp_line
			(start 2.999994 -2.999994)
			(end -2.999994 -2.999994)
			(stroke
				(width 0.1)
				(type default)
			)
			(layer "F.Fab")
		)
		(fp_line
			(start 2.999994 2.999994)
			(end 2.999994 -2.999994)
			(stroke
				(width 0.1)
				(type default)
			)
			(layer "F.Fab")
		)
		(fp_poly
			(pts
				(xy -4.318 -1.815338) (xy -4.318 -2.584704) (xy -3.548634 -2.199894)
			)
			(stroke
				(width 0)
				(type default)
			)
			(fill yes)
			(layer "F.Fab")
		)
		(pad "1" smd circle
			(at -2.949956 -2.199894 270)
			(size 0 0)
			(layers "F.Cu" "F.Mask" "F.Paste")
			(net "FM_CLK_EN_R")
		)
		(pad "2" smd circle
			(at -2.949956 -1.800098 270)
			(size 0 0)
			(layers "F.Cu" "F.Mask" "F.Paste")
			(net "GND")
		)
		(pad "3" smd circle
			(at -2.949956 -1.400048 270)
			(size 0 0)
			(layers "F.Cu" "F.Mask" "F.Paste")
			(net "P3V3_VDDAR_9ZXL0851_8_15")
		)
		(pad "4" smd circle
			(at -2.949956 -0.999998 270)
			(size 0 0)
			(layers "F.Cu" "F.Mask" "F.Paste")
			(net "CLK_100M_CK440Q_2_DB800ZL_R_DP")
		)
		(pad "5" smd circle
			(at -2.949956 -0.599948 270)
			(size 0 0)
			(layers "F.Cu" "F.Mask" "F.Paste")
			(net "CLK_100M_CK440Q_2_DB800ZL_R_DN")
		)
		(pad "6" smd circle
			(at -2.949956 -0.199898 270)
			(size 0 0)
			(layers "F.Cu" "F.Mask" "F.Paste")
			(net "SMB_BMC_9ZXL0851_8_15_SDA")
		)
		(pad "7" smd circle
			(at -2.949956 0.199898 270)
			(size 0 0)
			(layers "F.Cu" "F.Mask" "F.Paste")
			(net "SMB_BMC_9ZXL0851_8_15_SCL")
		)
		(pad "8" smd circle
			(at -2.949956 0.599948 270)
			(size 0 0)
			(layers "F.Cu" "F.Mask" "F.Paste")
			(net "Net_4347")
		)
		(pad "9" smd circle
			(at -2.949956 0.999998 270)
			(size 0 0)
			(layers "F.Cu" "F.Mask" "F.Paste")
			(net "Net_4346")
		)
		(pad "10" smd circle
			(at -2.949956 1.400048 270)
			(size 0 0)
			(layers "F.Cu" "F.Mask" "F.Paste")
			(net "P3V3_VDD_9ZXL0851_8_15")
		)
		(pad "11" smd circle
			(at -2.949956 1.800098 270)
			(size 0 0)
			(layers "F.Cu" "F.Mask" "F.Paste")
			(net "SSD8_CLK_EN_R_N")
		)
		(pad "12" smd circle
			(at -2.949956 2.199894 270)
			(size 0 0)
			(layers "F.Cu" "F.Mask" "F.Paste")
			(net "Net_4348")
		)
		(pad "13" smd circle
			(at -2.199894 2.949956)
			(size 0 0)
			(layers "F.Cu" "F.Mask" "F.Paste")
			(net "CLK_100M_DB800ZL_SSD8_DP")
		)
		(pad "14" smd circle
			(at -1.800098 2.949956)
			(size 0 0)
			(layers "F.Cu" "F.Mask" "F.Paste")
			(net "CLK_100M_DB800ZL_SSD8_DN")
		)
		(pad "15" smd circle
			(at -1.400048 2.949956)
			(size 0 0)
			(layers "F.Cu" "F.Mask" "F.Paste")
			(net "P3V3_VDD_9ZXL0851_8_15")
		)
		(pad "16" smd circle
			(at -0.999998 2.949956)
			(size 0 0)
			(layers "F.Cu" "F.Mask" "F.Paste")
			(net "CLK_100M_DB800ZL_SSD9_DP")
		)
		(pad "17" smd circle
			(at -0.599948 2.949956)
			(size 0 0)
			(layers "F.Cu" "F.Mask" "F.Paste")
			(net "CLK_100M_DB800ZL_SSD9_DN")
		)
		(pad "18" smd circle
			(at -0.199898 2.949956)
			(size 0 0)
			(layers "F.Cu" "F.Mask" "F.Paste")
			(net "SSD9_CLK_EN_R_N")
		)
		(pad "19" smd circle
			(at 0.199898 2.949956)
			(size 0 0)
			(layers "F.Cu" "F.Mask" "F.Paste")
			(net "P3V3_VDD_9ZXL0851_8_15")
		)
		(pad "20" smd circle
			(at 0.599948 2.949956)
			(size 0 0)
			(layers "F.Cu" "F.Mask" "F.Paste")
			(net "Net_4349")
		)
		(pad "21" smd circle
			(at 0.999998 2.949956)
			(size 0 0)
			(layers "F.Cu" "F.Mask" "F.Paste")
			(net "CLK_100M_DB800ZL_SSD10_DP")
		)
		(pad "22" smd circle
			(at 1.400048 2.949956)
			(size 0 0)
			(layers "F.Cu" "F.Mask" "F.Paste")
			(net "CLK_100M_DB800ZL_SSD10_DN")
		)
		(pad "23" smd circle
			(at 1.800098 2.949956)
			(size 0 0)
			(layers "F.Cu" "F.Mask" "F.Paste")
			(net "SSD10_CLK_EN_R_N")
		)
		(pad "24" smd circle
			(at 2.199894 2.949956)
			(size 0 0)
			(layers "F.Cu" "F.Mask" "F.Paste")
			(net "SSD11_CLK_EN_R_N")
		)
		(pad "25" smd circle
			(at 2.949956 2.199894 90)
			(size 0 0)
			(layers "F.Cu" "F.Mask" "F.Paste")
			(net "CLK_100M_DB800ZL_SSD11_DP")
		)
		(pad "26" smd circle
			(at 2.949956 1.800098 90)
			(size 0 0)
			(layers "F.Cu" "F.Mask" "F.Paste")
			(net "CLK_100M_DB800ZL_SSD11_DN")
		)
		(pad "27" smd circle
			(at 2.949956 1.400048 90)
			(size 0 0)
			(layers "F.Cu" "F.Mask" "F.Paste")
			(net "P3V3_VDD_9ZXL0851_8_15")
		)
		(pad "28" smd circle
			(at 2.949956 0.999998 90)
			(size 0 0)
			(layers "F.Cu" "F.Mask" "F.Paste")
			(net "CLK_100M_DB800ZL_SSD12_DP")
		)
		(pad "29" smd circle
			(at 2.949956 0.599948 90)
			(size 0 0)
			(layers "F.Cu" "F.Mask" "F.Paste")
			(net "CLK_100M_DB800ZL_SSD12_DN")
		)
		(pad "30" smd circle
			(at 2.949956 0.199898 90)
			(size 0 0)
			(layers "F.Cu" "F.Mask" "F.Paste")
			(net "SSD12_CLK_EN_R_N")
		)
		(pad "31" smd circle
			(at 2.949956 -0.199898 90)
			(size 0 0)
			(layers "F.Cu" "F.Mask" "F.Paste")
			(net "SSD13_CLK_EN_R_N")
		)
		(pad "32" smd circle
			(at 2.949956 -0.599948 90)
			(size 0 0)
			(layers "F.Cu" "F.Mask" "F.Paste")
			(net "CLK_100M_DB800ZL_SSD13_DP")
		)
		(pad "33" smd circle
			(at 2.949956 -0.999998 90)
			(size 0 0)
			(layers "F.Cu" "F.Mask" "F.Paste")
			(net "CLK_100M_DB800ZL_SSD13_DN")
		)
		(pad "34" smd circle
			(at 2.949956 -1.400048 90)
			(size 0 0)
			(layers "F.Cu" "F.Mask" "F.Paste")
			(net "P3V3_VDD_9ZXL0851_8_15")
		)
		(pad "35" smd circle
			(at 2.949956 -1.800098 90)
			(size 0 0)
			(layers "F.Cu" "F.Mask" "F.Paste")
			(net "CLK_100M_DB800ZL_SSD14_DP")
		)
		(pad "36" smd circle
			(at 2.949956 -2.199894 90)
			(size 0 0)
			(layers "F.Cu" "F.Mask" "F.Paste")
			(net "CLK_100M_DB800ZL_SSD14_DN")
		)
		(pad "37" smd circle
			(at 2.199894 -2.949956 180)
			(size 0 0)
			(layers "F.Cu" "F.Mask" "F.Paste")
			(net "SSD14_CLK_EN_R_N")
		)
		(pad "38" smd circle
			(at 1.800098 -2.949956 180)
			(size 0 0)
			(layers "F.Cu" "F.Mask" "F.Paste")
			(net "P3V3_VDD_9ZXL0851_8_15")
		)
		(pad "39" smd circle
			(at 1.400048 -2.949956 180)
			(size 0 0)
			(layers "F.Cu" "F.Mask" "F.Paste")
			(net "CLK_100M_DB800ZL_SSD15_DP")
		)
		(pad "40" smd circle
			(at 0.999998 -2.949956 180)
			(size 0 0)
			(layers "F.Cu" "F.Mask" "F.Paste")
			(net "CLK_100M_DB800ZL_SSD15_DN")
		)
		(pad "41" smd circle
			(at 0.599948 -2.949956 180)
			(size 0 0)
			(layers "F.Cu" "F.Mask" "F.Paste")
			(net "SSD15_CLK_EN_R_N")
		)
		(pad "42" smd circle
			(at 0.199898 -2.949956 180)
			(size 0 0)
			(layers "F.Cu" "F.Mask" "F.Paste")
			(net "P3V3_VDD_9ZXL0851_8_15")
		)
		(pad "43" smd circle
			(at -0.199898 -2.949956 180)
			(size 0 0)
			(layers "F.Cu" "F.Mask" "F.Paste")
			(net "Net_4350")
		)
		(pad "44" smd circle
			(at -0.599948 -2.949956 180)
			(size 0 0)
			(layers "F.Cu" "F.Mask" "F.Paste")
			(net "P3V3_VDDAR_9ZXL0851_8_15")
		)
		(pad "45" smd circle
			(at -0.999998 -2.949956 180)
			(size 0 0)
			(layers "F.Cu" "F.Mask" "F.Paste")
			(net "Net_4351")
		)
		(pad "46" smd circle
			(at -1.400048 -2.949956 180)
			(size 0 0)
			(layers "F.Cu" "F.Mask" "F.Paste")
			(net "Net_4352")
		)
		(pad "47" smd circle
			(at -1.800098 -2.949956 180)
			(size 0 0)
			(layers "F.Cu" "F.Mask" "F.Paste")
			(net "PU_9ZXL0851_8_15_100M")
		)
		(pad "48" smd circle
			(at -2.199894 -2.949956 180)
			(size 0 0)
			(layers "F.Cu" "F.Mask" "F.Paste")
			(net "PU_9ZXL0851_8_15_HBW")
		)
		(pad "49" smd rect
			(at 0 0)
			(size 4.2164 4.2164)
			(layers "F.Cu" "F.Mask" "F.Paste")
			(net "GND")
		)
		(zone
			(layer "F.Cu")
			(hatch none 0.5)
			(connect_pads
				(clearance 0)
			)
			(min_thickness 0.25)
			(keepout
				(tracks not_allowed)
				(vias allowed)
				(pads allowed)
				(copperpour not_allowed)
				(footprints allowed)
			)
			(placement
				(enabled no)
				(sheetname "")
			)
			(fill
				(thermal_gap 0.5)
				(thermal_bridge_width 0.5)
				(island_removal_mode 0)
			)
			(polygon
				(pts
					(xy 335.63179 -87.729568) (xy 335.63179 -84.300568) (xy 340.55939 -84.300568) (xy 340.55939 -89.228168)
					(xy 335.63179 -89.228168) (xy 335.63179 -87.754968) (xy 335.93659 -87.754968) (xy 335.93659 -88.923368)
					(xy 340.25459 -88.923368) (xy 340.25459 -84.605368) (xy 335.93659 -84.605368) (xy 335.93659 -87.729568)
				)
			)
		)
	)
	(footprint ""
		(layer "F.Cu")
		(at 331.175614 -120.493028)
		(property "Reference" "R4477"
			(at 0 0 0)
			(layer "F.SilkS")
			(hide yes)
			(effects
				(font
					(size 1.27 1.27)
				)
			)
		)
		(property "Value" ""
			(at 0 0 0)
			(layer "F.Fab")
			(effects
				(font
					(size 1.27 1.27)
				)
			)
		)
		(duplicate_pad_numbers_are_jumpers no)
		(fp_line
			(start -0.7874 -0.4064)
			(end 0.7874 -0.4064)
			(stroke
				(width 0.1524)
				(type default)
			)
			(layer "F.SilkS")
		)
		(fp_line
			(start -0.7874 0.4064)
			(end -0.7874 -0.4064)
			(stroke
				(width 0.1524)
				(type default)
			)
			(layer "F.SilkS")
		)
		(fp_line
			(start 0.7874 -0.4064)
			(end 0.7874 0.4064)
			(stroke
				(width 0.1524)
				(type default)
			)
			(layer "F.SilkS")
		)
		(fp_line
			(start 0.7874 0.4064)
			(end -0.7874 0.4064)
			(stroke
				(width 0.1524)
				(type default)
			)
			(layer "F.SilkS")
		)
		(fp_line
			(start -0.67945 -0.305054)
			(end -0.12065 -0.305054)
			(stroke
				(width 0.1)
				(type default)
			)
			(layer "F.Fab")
		)
		(fp_line
			(start -0.67945 0.3048)
			(end -0.67945 -0.305054)
			(stroke
				(width 0.1)
				(type default)
			)
			(layer "F.Fab")
		)
		(fp_line
			(start -0.12065 -0.305054)
			(end -0.12065 -0.2794)
			(stroke
				(width 0.1)
				(type default)
			)
			(layer "F.Fab")
		)
		(fp_line
			(start -0.12065 -0.2794)
			(end 0.12065 -0.2794)
			(stroke
				(width 0.1)
				(type default)
			)
			(layer "F.Fab")
		)
		(fp_line
			(start -0.12065 0.2794)
			(end -0.12065 0.3048)
			(stroke
				(width 0.1)
				(type default)
			)
			(layer "F.Fab")
		)
		(fp_line
			(start -0.12065 0.3048)
			(end -0.67945 0.3048)
			(stroke
				(width 0.1)
				(type default)
			)
			(layer "F.Fab")
		)
		(fp_line
			(start 0.120396 0.2794)
			(end -0.12065 0.2794)
			(stroke
				(width 0.1)
				(type default)
			)
			(layer "F.Fab")
		)
		(fp_line
			(start 0.120396 0.3048)
			(end 0.120396 0.2794)
			(stroke
				(width 0.1)
				(type default)
			)
			(layer "F.Fab")
		)
		(fp_line
			(start 0.12065 -0.3048)
			(end 0.67945 -0.3048)
			(stroke
				(width 0.1)
				(type default)
			)
			(layer "F.Fab")
		)
		(fp_line
			(start 0.12065 -0.2794)
			(end 0.12065 -0.3048)
			(stroke
				(width 0.1)
				(type default)
			)
			(layer "F.Fab")
		)
		(fp_line
			(start 0.67945 -0.3048)
			(end 0.67945 0.3048)
			(stroke
				(width 0.1)
				(type default)
			)
			(layer "F.Fab")
		)
		(fp_line
			(start 0.67945 0.3048)
			(end 0.120396 0.3048)
			(stroke
				(width 0.1)
				(type default)
			)
			(layer "F.Fab")
		)
		(pad "1" smd circle
			(at -0.40005 0)
			(size 0 0)
			(layers "F.Cu" "F.Mask" "F.Paste")
			(net "PWRGD_P3V3_NIC5")
		)
		(pad "2" smd circle
			(at 0.40005 0)
			(size 0 0)
			(layers "F.Cu" "F.Mask" "F.Paste")
			(net "PWRGD_P3V3_NIC5_R")
		)
	)
	(footprint ""
		(layer "F.Cu")
		(at 224.022158 -78.579472 180)
		(property "Reference" "R4347"
			(at 0 0 180)
			(layer "F.SilkS")
			(hide yes)
			(effects
				(font
					(size 1.27 1.27)
				)
			)
		)
		(property "Value" ""
			(at 0 0 180)
			(layer "F.Fab")
			(effects
				(font
					(size 1.27 1.27)
				)
			)
		)
		(duplicate_pad_numbers_are_jumpers no)
		(fp_line
			(start 0.7874 0.4064)
			(end -0.7874 0.4064)
			(stroke
				(width 0.1524)
				(type default)
			)
			(layer "F.SilkS")
		)
		(fp_line
			(start 0.7874 -0.4064)
			(end 0.7874 0.4064)
			(stroke
				(width 0.1524)
				(type default)
			)
			(layer "F.SilkS")
		)
		(fp_line
			(start -0.7874 0.4064)
			(end -0.7874 -0.4064)
			(stroke
				(width 0.1524)
				(type default)
			)
			(layer "F.SilkS")
		)
		(fp_line
			(start -0.7874 -0.4064)
			(end 0.7874 -0.4064)
			(stroke
				(width 0.1524)
				(type default)
			)
			(layer "F.SilkS")
		)
		(fp_line
			(start 0.67945 0.3048)
			(end 0.120396 0.3048)
			(stroke
				(width 0.1)
				(type default)
			)
			(layer "F.Fab")
		)
		(fp_line
			(start 0.67945 -0.3048)
			(end 0.67945 0.3048)
			(stroke
				(width 0.1)
				(type default)
			)
			(layer "F.Fab")
		)
		(fp_line
			(start 0.12065 -0.2794)
			(end 0.12065 -0.3048)
			(stroke
				(width 0.1)
				(type default)
			)
			(layer "F.Fab")
		)
		(fp_line
			(start 0.12065 -0.3048)
			(end 0.67945 -0.3048)
			(stroke
				(width 0.1)
				(type default)
			)
			(layer "F.Fab")
		)
		(fp_line
			(start 0.120396 0.3048)
			(end 0.120396 0.2794)
			(stroke
				(width 0.1)
				(type default)
			)
			(layer "F.Fab")
		)
		(fp_line
			(start 0.120396 0.2794)
			(end -0.12065 0.2794)
			(stroke
				(width 0.1)
				(type default)
			)
			(layer "F.Fab")
		)
		(fp_line
			(start -0.12065 0.3048)
			(end -0.67945 0.3048)
			(stroke
				(width 0.1)
				(type default)
			)
			(layer "F.Fab")
		)
		(fp_line
			(start -0.12065 0.2794)
			(end -0.12065 0.3048)
			(stroke
				(width 0.1)
				(type default)
			)
			(layer "F.Fab")
		)
		(fp_line
			(start -0.12065 -0.2794)
			(end 0.12065 -0.2794)
			(stroke
				(width 0.1)
				(type default)
			)
			(layer "F.Fab")
		)
		(fp_line
			(start -0.12065 -0.305054)
			(end -0.12065 -0.2794)
			(stroke
				(width 0.1)
				(type default)
			)
			(layer "F.Fab")
		)
		(fp_line
			(start -0.67945 0.3048)
			(end -0.67945 -0.305054)
			(stroke
				(width 0.1)
				(type default)
			)
			(layer "F.Fab")
		)
		(fp_line
			(start -0.67945 -0.305054)
			(end -0.12065 -0.305054)
			(stroke
				(width 0.1)
				(type default)
			)
			(layer "F.Fab")
		)
		(pad "1" smd circle
			(at -0.40005 0 180)
			(size 0 0)
			(layers "F.Cu" "F.Mask" "F.Paste")
			(net "P3V3_AUX")
		)
		(pad "2" smd circle
			(at 0.40005 0 180)
			(size 0 0)
			(layers "F.Cu" "F.Mask" "F.Paste")
			(net "SSD9_LED_R")
		)
	)
)
